(kicad_pcb
	(version 20260206)
	(generator "pcbnew")
	(generator_version "10.0")
	(general
		(thickness 1.6)
		(legacy_teardrops no)
	)
	(paper "A4")
	(title_block
		(title "12092022_DA0F0TMDCD0_F0T_Management_Board_D_brd_V3_OCP.brd")
		(comment 1 "Grand Teton / footprints 939-944 of 1440")
	)
	(layers
		(0 "F.Cu" signal "TOP")
		(4 "In1.Cu" signal "GND")
		(6 "In2.Cu" signal "IN1")
		(8 "In3.Cu" signal "GND1")
		(10 "In4.Cu" signal "IN2")
		(12 "In5.Cu" signal "VCC")
		(14 "In6.Cu" signal "VCC1")
		(16 "In7.Cu" signal "IN3")
		(18 "In8.Cu" signal "GND2")
		(20 "In9.Cu" signal "IN4")
		(22 "In10.Cu" signal "GND3")
		(2 "B.Cu" signal "BOTTOM")
		(9 "F.Adhes" user "F.Adhesive")
		(11 "B.Adhes" user "B.Adhesive")
		(13 "F.Paste" user "Package Geometry/Pastemask Top")
		(15 "B.Paste" user "Package Geometry/Pastemask Bottom")
		(5 "F.SilkS" user "Ref Des/Silkscreen Top")
		(7 "B.SilkS" user "Ref Des/Silkscreen Bottom")
		(1 "F.Mask" user "Board Geometry/Soldermask Top")
		(3 "B.Mask" user "Board Geometry/Soldermask Bottom")
		(17 "Dwgs.User" user "User.Drawings")
		(19 "Cmts.User" user "User.Comments")
		(21 "Eco1.User" user "User.Eco1")
		(23 "Eco2.User" user "User.Eco2")
		(25 "Edge.Cuts" user "Board Geometry/Outline")
		(27 "Margin" user)
		(31 "F.CrtYd" user "Package Geometry/Place Bound Top")
		(29 "B.CrtYd" user "Package Geometry/Place Bound Bottom")
		(35 "F.Fab" user "Ref Des/Assembly Top")
		(33 "B.Fab" user "Ref Des/Assembly Bottom")
	)
	(footprint ""
		(layer "B.Cu")
		(at 54.684676 -30.867604 -90)
		(property "Reference" "R262"
			(at 0 0 90)
			(layer "B.SilkS")
			(hide yes)
			(effects
				(font
					(size 1.27 1.27)
				)
				(justify mirror)
			)
		)
		(property "Value" ""
			(at 0 0 90)
			(layer "B.Fab")
			(effects
				(font
					(size 1.27 1.27)
				)
				(justify mirror)
			)
		)
		(duplicate_pad_numbers_are_jumpers no)
		(fp_line
			(start -0.7874 0.4064)
			(end 0.7874 0.4064)
			(stroke
				(width 0.1524)
				(type default)
			)
			(layer "B.SilkS")
		)
		(fp_line
			(start 0.7874 0.4064)
			(end 0.7874 -0.4064)
			(stroke
				(width 0.1524)
				(type default)
			)
			(layer "B.SilkS")
		)
		(fp_line
			(start -0.7874 -0.4064)
			(end -0.7874 0.4064)
			(stroke
				(width 0.1524)
				(type default)
			)
			(layer "B.SilkS")
		)
		(fp_line
			(start 0.7874 -0.4064)
			(end -0.7874 -0.4064)
			(stroke
				(width 0.1524)
				(type default)
			)
			(layer "B.SilkS")
		)
		(fp_line
			(start -0.67945 0.3048)
			(end -0.120396 0.3048)
			(stroke
				(width 0.1)
				(type default)
			)
			(layer "B.Fab")
		)
		(fp_line
			(start -0.120396 0.3048)
			(end -0.120396 0.2794)
			(stroke
				(width 0.1)
				(type default)
			)
			(layer "B.Fab")
		)
		(fp_line
			(start 0.12065 0.3048)
			(end 0.67945 0.3048)
			(stroke
				(width 0.1)
				(type default)
			)
			(layer "B.Fab")
		)
		(fp_line
			(start 0.67945 0.3048)
			(end 0.67945 -0.305054)
			(stroke
				(width 0.1)
				(type default)
			)
			(layer "B.Fab")
		)
		(fp_line
			(start -0.120396 0.2794)
			(end 0.12065 0.2794)
			(stroke
				(width 0.1)
				(type default)
			)
			(layer "B.Fab")
		)
		(fp_line
			(start 0.12065 0.2794)
			(end 0.12065 0.3048)
			(stroke
				(width 0.1)
				(type default)
			)
			(layer "B.Fab")
		)
		(fp_line
			(start -0.12065 -0.2794)
			(end -0.12065 -0.3048)
			(stroke
				(width 0.1)
				(type default)
			)
			(layer "B.Fab")
		)
		(fp_line
			(start 0.12065 -0.2794)
			(end -0.12065 -0.2794)
			(stroke
				(width 0.1)
				(type default)
			)
			(layer "B.Fab")
		)
		(fp_line
			(start -0.67945 -0.3048)
			(end -0.67945 0.3048)
			(stroke
				(width 0.1)
				(type default)
			)
			(layer "B.Fab")
		)
		(fp_line
			(start -0.12065 -0.3048)
			(end -0.67945 -0.3048)
			(stroke
				(width 0.1)
				(type default)
			)
			(layer "B.Fab")
		)
		(fp_line
			(start 0.12065 -0.305054)
			(end 0.12065 -0.2794)
			(stroke
				(width 0.1)
				(type default)
			)
			(layer "B.Fab")
		)
		(fp_line
			(start 0.67945 -0.305054)
			(end 0.12065 -0.305054)
			(stroke
				(width 0.1)
				(type default)
			)
			(layer "B.Fab")
		)
		(pad "1" smd circle
			(at 0.40005 0 90)
			(size 0 0)
			(layers "B.Cu" "B.Mask" "B.Paste")
			(net "P3V3_AUX")
		)
		(pad "2" smd circle
			(at -0.40005 0 90)
			(size 0 0)
			(layers "B.Cu" "B.Mask" "B.Paste")
			(net "SMB_BMC_MM10_SCL")
		)
	)
	(footprint ""
		(layer "B.Cu")
		(at 85.29955 -46.463204 180)
		(property "Reference" "R372"
			(at 0 0 0)
			(layer "B.SilkS")
			(hide yes)
			(effects
				(font
					(size 1.27 1.27)
				)
				(justify mirror)
			)
		)
		(property "Value" ""
			(at 0 0 0)
			(layer "B.Fab")
			(effects
				(font
					(size 1.27 1.27)
				)
				(justify mirror)
			)
		)
		(duplicate_pad_numbers_are_jumpers no)
		(fp_line
			(start 0.7874 0.4064)
			(end 0.7874 -0.4064)
			(stroke
				(width 0.1524)
				(type default)
			)
			(layer "B.SilkS")
		)
		(fp_line
			(start 0.7874 -0.4064)
			(end -0.7874 -0.4064)
			(stroke
				(width 0.1524)
				(type default)
			)
			(layer "B.SilkS")
		)
		(fp_line
			(start -0.7874 0.4064)
			(end 0.7874 0.4064)
			(stroke
				(width 0.1524)
				(type default)
			)
			(layer "B.SilkS")
		)
		(fp_line
			(start -0.7874 -0.4064)
			(end -0.7874 0.4064)
			(stroke
				(width 0.1524)
				(type default)
			)
			(layer "B.SilkS")
		)
		(fp_line
			(start 0.67945 0.3048)
			(end 0.67945 -0.305054)
			(stroke
				(width 0.1)
				(type default)
			)
			(layer "B.Fab")
		)
		(fp_line
			(start 0.67945 -0.305054)
			(end 0.12065 -0.305054)
			(stroke
				(width 0.1)
				(type default)
			)
			(layer "B.Fab")
		)
		(fp_line
			(start 0.12065 0.3048)
			(end 0.67945 0.3048)
			(stroke
				(width 0.1)
				(type default)
			)
			(layer "B.Fab")
		)
		(fp_line
			(start 0.12065 0.2794)
			(end 0.12065 0.3048)
			(stroke
				(width 0.1)
				(type default)
			)
			(layer "B.Fab")
		)
		(fp_line
			(start 0.12065 -0.2794)
			(end -0.12065 -0.2794)
			(stroke
				(width 0.1)
				(type default)
			)
			(layer "B.Fab")
		)
		(fp_line
			(start 0.12065 -0.305054)
			(end 0.12065 -0.2794)
			(stroke
				(width 0.1)
				(type default)
			)
			(layer "B.Fab")
		)
		(fp_line
			(start -0.120396 0.3048)
			(end -0.120396 0.2794)
			(stroke
				(width 0.1)
				(type default)
			)
			(layer "B.Fab")
		)
		(fp_line
			(start -0.120396 0.2794)
			(end 0.12065 0.2794)
			(stroke
				(width 0.1)
				(type default)
			)
			(layer "B.Fab")
		)
		(fp_line
			(start -0.12065 -0.2794)
			(end -0.12065 -0.3048)
			(stroke
				(width 0.1)
				(type default)
			)
			(layer "B.Fab")
		)
		(fp_line
			(start -0.12065 -0.3048)
			(end -0.67945 -0.3048)
			(stroke
				(width 0.1)
				(type default)
			)
			(layer "B.Fab")
		)
		(fp_line
			(start -0.67945 0.3048)
			(end -0.120396 0.3048)
			(stroke
				(width 0.1)
				(type default)
			)
			(layer "B.Fab")
		)
		(fp_line
			(start -0.67945 -0.3048)
			(end -0.67945 0.3048)
			(stroke
				(width 0.1)
				(type default)
			)
			(layer "B.Fab")
		)
		(pad "1" smd circle
			(at 0.40005 0)
			(size 0 0)
			(layers "B.Cu" "B.Mask" "B.Paste")
			(net "M_BMC_DDR4_MBA1")
		)
		(pad "2" smd circle
			(at -0.40005 0)
			(size 0 0)
			(layers "B.Cu" "B.Mask" "B.Paste")
			(net "P1V2_AUX")
		)
	)
	(footprint ""
		(layer "B.Cu")
		(at 41.91 -42.037 180)
		(property "Reference" "R689"
			(at 0 0 0)
			(layer "B.SilkS")
			(hide yes)
			(effects
				(font
					(size 1.27 1.27)
				)
				(justify mirror)
			)
		)
		(property "Value" ""
			(at 0 0 0)
			(layer "B.Fab")
			(effects
				(font
					(size 1.27 1.27)
				)
				(justify mirror)
			)
		)
		(duplicate_pad_numbers_are_jumpers no)
		(fp_line
			(start 0.7874 0.4064)
			(end 0.7874 -0.4064)
			(stroke
				(width 0.1524)
				(type default)
			)
			(layer "B.SilkS")
		)
		(fp_line
			(start 0.7874 -0.4064)
			(end -0.7874 -0.4064)
			(stroke
				(width 0.1524)
				(type default)
			)
			(layer "B.SilkS")
		)
		(fp_line
			(start -0.7874 0.4064)
			(end 0.7874 0.4064)
			(stroke
				(width 0.1524)
				(type default)
			)
			(layer "B.SilkS")
		)
		(fp_line
			(start -0.7874 -0.4064)
			(end -0.7874 0.4064)
			(stroke
				(width 0.1524)
				(type default)
			)
			(layer "B.SilkS")
		)
		(fp_line
			(start 0.67945 0.3048)
			(end 0.67945 -0.305054)
			(stroke
				(width 0.1)
				(type default)
			)
			(layer "B.Fab")
		)
		(fp_line
			(start 0.67945 -0.305054)
			(end 0.12065 -0.305054)
			(stroke
				(width 0.1)
				(type default)
			)
			(layer "B.Fab")
		)
		(fp_line
			(start 0.12065 0.3048)
			(end 0.67945 0.3048)
			(stroke
				(width 0.1)
				(type default)
			)
			(layer "B.Fab")
		)
		(fp_line
			(start 0.12065 0.2794)
			(end 0.12065 0.3048)
			(stroke
				(width 0.1)
				(type default)
			)
			(layer "B.Fab")
		)
		(fp_line
			(start 0.12065 -0.2794)
			(end -0.12065 -0.2794)
			(stroke
				(width 0.1)
				(type default)
			)
			(layer "B.Fab")
		)
		(fp_line
			(start 0.12065 -0.305054)
			(end 0.12065 -0.2794)
			(stroke
				(width 0.1)
				(type default)
			)
			(layer "B.Fab")
		)
		(fp_line
			(start -0.120396 0.3048)
			(end -0.120396 0.2794)
			(stroke
				(width 0.1)
				(type default)
			)
			(layer "B.Fab")
		)
		(fp_line
			(start -0.120396 0.2794)
			(end 0.12065 0.2794)
			(stroke
				(width 0.1)
				(type default)
			)
			(layer "B.Fab")
		)
		(fp_line
			(start -0.12065 -0.2794)
			(end -0.12065 -0.3048)
			(stroke
				(width 0.1)
				(type default)
			)
			(layer "B.Fab")
		)
		(fp_line
			(start -0.12065 -0.3048)
			(end -0.67945 -0.3048)
			(stroke
				(width 0.1)
				(type default)
			)
			(layer "B.Fab")
		)
		(fp_line
			(start -0.67945 0.3048)
			(end -0.120396 0.3048)
			(stroke
				(width 0.1)
				(type default)
			)
			(layer "B.Fab")
		)
		(fp_line
			(start -0.67945 -0.3048)
			(end -0.67945 0.3048)
			(stroke
				(width 0.1)
				(type default)
			)
			(layer "B.Fab")
		)
		(pad "1" smd circle
			(at 0.40005 0)
			(size 0 0)
			(layers "B.Cu" "B.Mask" "B.Paste")
			(net "IRQ_SGPIO_N")
		)
		(pad "2" smd circle
			(at -0.40005 0)
			(size 0 0)
			(layers "B.Cu" "B.Mask" "B.Paste")
			(net "IRQ_SGPIO_BMC_N")
		)
	)
	(footprint ""
		(layer "B.Cu")
		(at 68.6308 -93.7514 90)
		(property "Reference" "R645"
			(at 0 0 90)
			(layer "B.SilkS")
			(hide yes)
			(effects
				(font
					(size 1.27 1.27)
				)
				(justify mirror)
			)
		)
		(property "Value" ""
			(at 0 0 90)
			(layer "B.Fab")
			(effects
				(font
					(size 1.27 1.27)
				)
				(justify mirror)
			)
		)
		(duplicate_pad_numbers_are_jumpers no)
		(fp_line
			(start 1.2954 -0.5842)
			(end -1.2954 -0.5842)
			(stroke
				(width 0.1524)
				(type default)
			)
			(layer "B.SilkS")
		)
		(fp_line
			(start -1.2954 -0.5842)
			(end -1.2954 0.5842)
			(stroke
				(width 0.1524)
				(type default)
			)
			(layer "B.SilkS")
		)
		(fp_line
			(start 1.2954 0.5842)
			(end 1.2954 -0.5842)
			(stroke
				(width 0.1524)
				(type default)
			)
			(layer "B.SilkS")
		)
		(fp_line
			(start -1.2954 0.5842)
			(end 1.2954 0.5842)
			(stroke
				(width 0.1524)
				(type default)
			)
			(layer "B.SilkS")
		)
		(fp_line
			(start 0.8636 -0.4572)
			(end -0.8636 -0.4572)
			(stroke
				(width 0.1)
				(type default)
			)
			(layer "B.Fab")
		)
		(fp_line
			(start -0.8636 -0.4572)
			(end -0.8636 -0.406654)
			(stroke
				(width 0.1)
				(type default)
			)
			(layer "B.Fab")
		)
		(fp_line
			(start 1.1938 -0.406654)
			(end 0.8636 -0.406654)
			(stroke
				(width 0.1)
				(type default)
			)
			(layer "B.Fab")
		)
		(fp_line
			(start 0.8636 -0.406654)
			(end 0.8636 -0.4572)
			(stroke
				(width 0.1)
				(type default)
			)
			(layer "B.Fab")
		)
		(fp_line
			(start -0.8636 -0.406654)
			(end -1.1938 -0.406654)
			(stroke
				(width 0.1)
				(type default)
			)
			(layer "B.Fab")
		)
		(fp_line
			(start -1.1938 -0.406654)
			(end -1.1938 0.4064)
			(stroke
				(width 0.1)
				(type default)
			)
			(layer "B.Fab")
		)
		(fp_line
			(start 1.1938 0.4064)
			(end 1.1938 -0.406654)
			(stroke
				(width 0.1)
				(type default)
			)
			(layer "B.Fab")
		)
		(fp_line
			(start 0.8636 0.4064)
			(end 1.1938 0.4064)
			(stroke
				(width 0.1)
				(type default)
			)
			(layer "B.Fab")
		)
		(fp_line
			(start -0.8636 0.4064)
			(end -0.8636 0.4572)
			(stroke
				(width 0.1)
				(type default)
			)
			(layer "B.Fab")
		)
		(fp_line
			(start -1.1938 0.4064)
			(end -0.8636 0.4064)
			(stroke
				(width 0.1)
				(type default)
			)
			(layer "B.Fab")
		)
		(fp_line
			(start 0.8636 0.4318)
			(end 0.8636 0.4064)
			(stroke
				(width 0.1)
				(type default)
			)
			(layer "B.Fab")
		)
		(fp_line
			(start 0.8636 0.4572)
			(end 0.8636 0.4318)
			(stroke
				(width 0.1)
				(type default)
			)
			(layer "B.Fab")
		)
		(fp_line
			(start -0.8636 0.4572)
			(end 0.8636 0.4572)
			(stroke
				(width 0.1)
				(type default)
			)
			(layer "B.Fab")
		)
		(pad "1" smd rect
			(at 0.7366 0)
			(size 0.7112 0.8128)
			(layers "B.Cu" "B.Mask" "B.Paste")
			(net "P1V8_AUX")
		)
		(pad "2" smd rect
			(at -0.7366 0)
			(size 0.7112 0.8128)
			(layers "B.Cu" "B.Mask" "B.Paste")
			(net "PGPPA_BMC_AUX_L")
		)
	)
	(footprint ""
		(layer "B.Cu")
		(at 114.554 34.6964 -90)
		(property "Reference" "X20"
			(at 2.04597 1.2065 0)
			(unlocked yes)
			(layer "B.SilkS")
			(effects
				(font
					(size 0.7874 0.5842)
					(thickness 0.1524)
				)
				(justify left mirror)
			)
		)
		(property "Value" ""
			(at 0 0 90)
			(layer "B.Fab")
			(effects
				(font
					(size 1.27 1.27)
				)
				(justify mirror)
			)
		)
		(property "Device Type" "TP_TDR_4P_FTS_TH-TP_TDR_4P_DIPA"
			(at -1.30175 1.27 180)
			(unlocked yes)
			(layer "B.Fab")
			(hide yes)
			(effects
				(font
					(size 0.635 0.4064)
					(thickness 0.1524)
				)
				(justify mirror)
			)
		)
		(property "User Part Number" "N_A"
			(at -1.30175 1.27 180)
			(unlocked yes)
			(layer "Cmts.User")
			(hide yes)
			(effects
				(font
					(size 0.635 0.4064)
					(thickness 0.1524)
				)
				(justify mirror)
			)
		)
		(duplicate_pad_numbers_are_jumpers no)
		(fp_line
			(start -2.54 3.81)
			(end -2.54 3.6703)
			(stroke
				(width 0.1524)
				(type default)
			)
			(layer "B.SilkS")
		)
		(fp_line
			(start 0 3.81)
			(end -2.54 3.81)
			(stroke
				(width 0.1524)
				(type default)
			)
			(layer "B.SilkS")
		)
		(fp_line
			(start 0 3.175)
			(end 0 3.81)
			(stroke
				(width 0.1524)
				(type default)
			)
			(layer "B.SilkS")
		)
		(fp_line
			(start -2.54 1.4097)
			(end -2.54 1.1303)
			(stroke
				(width 0.1524)
				(type default)
			)
			(layer "B.SilkS")
		)
		(fp_line
			(start 0 0.635)
			(end 0 1.905)
			(stroke
				(width 0.1524)
				(type default)
			)
			(layer "B.SilkS")
		)
		(fp_line
			(start -2.54 -1.1303)
			(end -2.54 -1.27)
			(stroke
				(width 0.1524)
				(type default)
			)
			(layer "B.SilkS")
		)
		(fp_line
			(start -2.54 -1.27)
			(end 0 -1.27)
			(stroke
				(width 0.1524)
				(type default)
			)
			(layer "B.SilkS")
		)
		(fp_line
			(start 0 -1.27)
			(end 0 -0.635)
			(stroke
				(width 0.1524)
				(type default)
			)
			(layer "B.SilkS")
		)
		(fp_poly
			(pts
				(xy 0.761746 0) (xy 2.285746 -0.762) (xy 2.285746 0.762)
			)
			(stroke
				(width 0)
				(type default)
			)
			(fill yes)
			(layer "B.SilkS")
		)
		(fp_line
			(start -2.54 3.81)
			(end -2.54 -1.27)
			(stroke
				(width 0.1)
				(type default)
			)
			(layer "B.Fab")
		)
		(fp_line
			(start 0 3.81)
			(end -2.54 3.81)
			(stroke
				(width 0.1)
				(type default)
			)
			(layer "B.Fab")
		)
		(fp_line
			(start -2.54 -1.27)
			(end 0 -1.27)
			(stroke
				(width 0.1)
				(type default)
			)
			(layer "B.Fab")
		)
		(fp_line
			(start 0 -1.27)
			(end 0 3.81)
			(stroke
				(width 0.1)
				(type default)
			)
			(layer "B.Fab")
		)
		(fp_poly
			(pts
				(xy 0.761746 0) (xy 2.285746 -0.762) (xy 2.285746 0.762)
			)
			(stroke
				(width 0)
				(type default)
			)
			(fill yes)
			(layer "B.Fab")
		)
		(pad "1" thru_hole circle
			(at 0 0 90)
			(size 1.0033 1.0033)
			(drill 0.249936)
			(layers "*.Cu" "*.Mask")
			(remove_unused_layers no)
			(net "TDR_DIFF_100_IN1_DN")
			(clearance 0.10795)
			(padstack
				(mode front_inner_back)
				(layer "Inner"
					(shape circle)
					(size 0.8001 0.8001)
					(clearance 0.1524)
				)
				(layer "B.Cu"
					(shape circle)
					(size 1.0033 1.0033)
					(thermal_gap 0.10795)
					(clearance 0.10795)
				)
			)
		)
		(pad "2" thru_hole circle
			(at -2.54 0 90)
			(size 1.9939 1.9939)
			(drill 0.249936)
			(layers "*.Cu" "*.Mask")
			(remove_unused_layers no)
			(net "GND_P1")
			(clearance 0.10795)
			(padstack
				(mode front_inner_back)
				(layer "Inner"
					(shape circle)
					(size 0.8001 0.8001)
					(clearance 0.1524)
				)
				(layer "B.Cu"
					(shape circle)
					(size 1.9939 1.9939)
					(thermal_gap 0.10795)
					(clearance 0.10795)
				)
			)
		)
		(pad "3" thru_hole circle
			(at -2.54 2.54 90)
			(size 1.9939 1.9939)
			(drill 0.249936)
			(layers "*.Cu" "*.Mask")
			(remove_unused_layers no)
			(net "GND_P1")
			(clearance 0.10795)
			(padstack
				(mode front_inner_back)
				(layer "Inner"
					(shape circle)
					(size 0.8001 0.8001)
					(clearance 0.1524)
				)
				(layer "B.Cu"
					(shape circle)
					(size 1.9939 1.9939)
					(thermal_gap 0.10795)
					(clearance 0.10795)
				)
			)
		)
		(pad "4" thru_hole circle
			(at 0 2.54 90)
			(size 1.0033 1.0033)
			(drill 0.249936)
			(layers "*.Cu" "*.Mask")
			(remove_unused_layers no)
			(net "TDR_DIFF_100_IN1_DP")
			(clearance 0.10795)
			(padstack
				(mode front_inner_back)
				(layer "Inner"
					(shape circle)
					(size 0.8001 0.8001)
					(clearance 0.1524)
				)
				(layer "B.Cu"
					(shape circle)
					(size 1.0033 1.0033)
					(thermal_gap 0.10795)
					(clearance 0.10795)
				)
			)
		)
	)
	(footprint ""
		(layer "B.Cu")
		(at 22.65934 -91.187016 90)
		(property "Reference" "C166"
			(at 0 0 90)
			(layer "B.SilkS")
			(hide yes)
			(effects
				(font
					(size 1.27 1.27)
				)
				(justify mirror)
			)
		)
		(property "Value" ""
			(at 0 0 90)
			(layer "B.Fab")
			(effects
				(font
					(size 1.27 1.27)
				)
				(justify mirror)
			)
		)
		(duplicate_pad_numbers_are_jumpers no)
		(fp_line
			(start 0.69215 -0.2921)
			(end -0.69215 -0.2921)
			(stroke
				(width 0.1524)
				(type default)
			)
			(layer "B.SilkS")
		)
		(fp_line
			(start -0.69215 -0.2921)
			(end -0.69215 0.2921)
			(stroke
				(width 0.1524)
				(type default)
			)
			(layer "B.SilkS")
		)
		(fp_line
			(start 0.69215 0.2921)
			(end 0.69215 -0.2921)
			(stroke
				(width 0.1524)
				(type default)
			)
			(layer "B.SilkS")
		)
		(fp_line
			(start -0.69215 0.2921)
			(end 0.69215 0.2921)
			(stroke
				(width 0.1524)
				(type default)
			)
			(layer "B.SilkS")
		)
		(fp_line
			(start 0.51435 -0.2794)
			(end -0.51435 -0.2794)
			(stroke
				(width 0.1)
				(type default)
			)
			(layer "B.Fab")
		)
		(fp_line
			(start -0.51435 -0.2794)
			(end -0.51435 0.2794)
			(stroke
				(width 0.1)
				(type default)
			)
			(layer "B.Fab")
		)
		(fp_line
			(start 0.51435 0.2794)
			(end 0.51435 -0.2794)
			(stroke
				(width 0.1)
				(type default)
			)
			(layer "B.Fab")
		)
		(fp_line
			(start -0.51435 0.2794)
			(end 0.51435 0.2794)
			(stroke
				(width 0.1)
				(type default)
			)
			(layer "B.Fab")
		)
		(pad "1" smd circle
			(at 0.40005 0 270)
			(size 0 0)
			(layers "B.Cu" "B.Mask" "B.Paste")
			(net "VCCIO0")
		)
		(pad "2" smd circle
			(at -0.40005 0 270)
			(size 0 0)
			(layers "B.Cu" "B.Mask" "B.Paste")
			(net "GND")
		)
		(zone
			(layer "B.Cu")
			(hatch none 0.5)
			(connect_pads
				(clearance 0)
			)
			(min_thickness 0.25)
			(keepout
				(tracks not_allowed)
				(vias allowed)
				(pads allowed)
				(copperpour not_allowed)
				(footprints allowed)
			)
			(placement
				(enabled no)
				(sheetname "")
			)
			(fill
				(thermal_gap 0.5)
				(thermal_bridge_width 0.5)
				(island_removal_mode 0)
			)
			(polygon
				(pts
					(xy 22.74697 -91.377516) (xy 22.805136 -91.286076) (xy 22.805136 -91.086686) (xy 22.74697 -90.996516)
					(xy 22.57171 -90.996516) (xy 22.51329 -91.086686) (xy 22.51329 -91.286076) (xy 22.571456 -91.377516)
				)
			)
		)
	)
)
